# T6G (Grand Teton) — schematic netlist excerpt (pin names and nets, part order shuffled) for the footprints in the layout excerpt that follows; sources: Cadence DE-HDL packaged netlist, KiCad conversion of 04192023_DAF0TMB3IC0_F0TG_MB_C_brd_V02_OCP.brd

R2624  Q_RES  49.9 1% CHIP  pkg 0402LF  page 267 : A = P12V_HSC_TEMP_E ; B = P12V_HSC_TEMP_D-
C193  Q_CAP  100NF 50V 10% X7R  pkg C0402  page 187 : A = P1V5_BAT_IN ; B = GND

(kicad_pcb
	(version 20260206)
	(generator "pcbnew")
	(generator_version "10.0")
	(general
		(thickness 1.6)
		(legacy_teardrops no)
	)
	(paper "A4")
	(title_block
		(title "04192023_DAF0TMB3IC0_F0TG_MB_C_brd_V02_OCP.brd")
		(comment 1 "Grand Teton / footprints 2561-2562 of 8354")
	)
	(layers
		(0 "F.Cu" signal "TOP")
		(4 "In1.Cu" signal "GND")
		(6 "In2.Cu" signal "IN1")
		(8 "In3.Cu" signal "GND1")
		(10 "In4.Cu" signal "IN2")
		(12 "In5.Cu" signal "GND2")
		(14 "In6.Cu" signal "IN3")
		(16 "In7.Cu" signal "GND3")
		(18 "In8.Cu" signal "VCC")
		(20 "In9.Cu" signal "VCC1")
		(22 "In10.Cu" signal "GND4")
		(24 "In11.Cu" signal "IN4")
		(26 "In12.Cu" signal "GND5")
		(28 "In13.Cu" signal "IN5")
		(30 "In14.Cu" signal "GND6")
		(32 "In15.Cu" signal "IN6")
		(34 "In16.Cu" signal "GND7")
		(2 "B.Cu" signal "BOTTOM")
		(9 "F.Adhes" user "F.Adhesive")
		(11 "B.Adhes" user "B.Adhesive")
		(13 "F.Paste" user "Package Geometry/Pastemask Top")
		(15 "B.Paste" user "Package Geometry/Pastemask Bottom")
		(5 "F.SilkS" user "Ref Des/Silkscreen Top")
		(7 "B.SilkS" user "Ref Des/Silkscreen Bottom")
		(1 "F.Mask" user "Board Geometry/Soldermask Top")
		(3 "B.Mask" user "Board Geometry/Soldermask Bottom")
		(17 "Dwgs.User" user "User.Drawings")
		(19 "Cmts.User" user "User.Comments")
		(21 "Eco1.User" user "User.Eco1")
		(23 "Eco2.User" user "User.Eco2")
		(25 "Edge.Cuts" user "Board Geometry/Outline")
		(27 "Margin" user)
		(31 "F.CrtYd" user "Package Geometry/Place Bound Top")
		(29 "B.CrtYd" user "Package Geometry/Place Bound Bottom")
		(35 "F.Fab" user "Ref Des/Assembly Top")
		(33 "B.Fab" user "Ref Des/Assembly Bottom")
	)
	(footprint ""
		(layer "F.Cu")
		(at 298.050966 -22.747224)
		(property "Reference" "C193"
			(at 0 0 0)
			(layer "F.SilkS")
			(hide yes)
			(effects
				(font
					(size 1.27 1.27)
				)
			)
		)
		(property "Value" ""
			(at 0 0 0)
			(layer "F.Fab")
			(effects
				(font
					(size 1.27 1.27)
				)
			)
		)
		(duplicate_pad_numbers_are_jumpers no)
		(fp_line
			(start -0.7874 -0.4064)
			(end 0.7874 -0.4064)
			(stroke
				(width 0.1524)
				(type default)
			)
			(layer "F.SilkS")
		)
		(fp_line
			(start -0.7874 0.4064)
			(end -0.7874 -0.4064)
			(stroke
				(width 0.1524)
				(type default)
			)
			(layer "F.SilkS")
		)
		(fp_line
			(start 0.7874 -0.4064)
			(end 0.7874 0.4064)
			(stroke
				(width 0.1524)
				(type default)
			)
			(layer "F.SilkS")
		)
		(fp_line
			(start 0.7874 0.4064)
			(end -0.7874 0.4064)
			(stroke
				(width 0.1524)
				(type default)
			)
			(layer "F.SilkS")
		)
		(fp_line
			(start -0.67945 -0.305054)
			(end -0.12065 -0.305054)
			(stroke
				(width 0.1)
				(type default)
			)
			(layer "F.Fab")
		)
		(fp_line
			(start -0.67945 0.3048)
			(end -0.67945 -0.305054)
			(stroke
				(width 0.1)
				(type default)
			)
			(layer "F.Fab")
		)
		(fp_line
			(start -0.12065 -0.305054)
			(end -0.12065 -0.2794)
			(stroke
				(width 0.1)
				(type default)
			)
			(layer "F.Fab")
		)
		(fp_line
			(start -0.12065 -0.2794)
			(end 0.12065 -0.2794)
			(stroke
				(width 0.1)
				(type default)
			)
			(layer "F.Fab")
		)
		(fp_line
			(start -0.12065 0.2794)
			(end -0.12065 0.3048)
			(stroke
				(width 0.1)
				(type default)
			)
			(layer "F.Fab")
		)
		(fp_line
			(start -0.12065 0.3048)
			(end -0.67945 0.3048)
			(stroke
				(width 0.1)
				(type default)
			)
			(layer "F.Fab")
		)
		(fp_line
			(start 0.120396 0.2794)
			(end -0.12065 0.2794)
			(stroke
				(width 0.1)
				(type default)
			)
			(layer "F.Fab")
		)
		(fp_line
			(start 0.120396 0.3048)
			(end 0.120396 0.2794)
			(stroke
				(width 0.1)
				(type default)
			)
			(layer "F.Fab")
		)
		(fp_line
			(start 0.12065 -0.3048)
			(end 0.67945 -0.3048)
			(stroke
				(width 0.1)
				(type default)
			)
			(layer "F.Fab")
		)
		(fp_line
			(start 0.12065 -0.2794)
			(end 0.12065 -0.3048)
			(stroke
				(width 0.1)
				(type default)
			)
			(layer "F.Fab")
		)
		(fp_line
			(start 0.67945 -0.3048)
			(end 0.67945 0.3048)
			(stroke
				(width 0.1)
				(type default)
			)
			(layer "F.Fab")
		)
		(fp_line
			(start 0.67945 0.3048)
			(end 0.120396 0.3048)
			(stroke
				(width 0.1)
				(type default)
			)
			(layer "F.Fab")
		)
		(pad "1" smd circle
			(at -0.40005 0)
			(size 0 0)
			(layers "F.Cu" "F.Mask" "F.Paste")
			(net "P1V5_BAT_IN")
		)
		(pad "2" smd circle
			(at 0.40005 0)
			(size 0 0)
			(layers "F.Cu" "F.Mask" "F.Paste")
			(net "GND")
		)
	)
	(footprint ""
		(layer "F.Cu")
		(at 284.73654 -403.961092 -90)
		(property "Reference" "R2624"
			(at 0 0 270)
			(layer "F.SilkS")
			(hide yes)
			(effects
				(font
					(size 1.27 1.27)
				)
			)
		)
		(property "Value" ""
			(at 0 0 270)
			(layer "F.Fab")
			(effects
				(font
					(size 1.27 1.27)
				)
			)
		)
		(duplicate_pad_numbers_are_jumpers no)
		(fp_line
			(start -0.7874 0.4064)
			(end -0.7874 -0.4064)
			(stroke
				(width 0.1524)
				(type default)
			)
			(layer "F.SilkS")
		)
		(fp_line
			(start 0.7874 0.4064)
			(end -0.7874 0.4064)
			(stroke
				(width 0.1524)
				(type default)
			)
			(layer "F.SilkS")
		)
		(fp_line
			(start -0.7874 -0.4064)
			(end 0.7874 -0.4064)
			(stroke
				(width 0.1524)
				(type default)
			)
			(layer "F.SilkS")
		)
		(fp_line
			(start 0.7874 -0.4064)
			(end 0.7874 0.4064)
			(stroke
				(width 0.1524)
				(type default)
			)
			(layer "F.SilkS")
		)
		(fp_line
			(start -0.67945 0.3048)
			(end -0.67945 -0.305054)
			(stroke
				(width 0.1)
				(type default)
			)
			(layer "F.Fab")
		)
		(fp_line
			(start -0.12065 0.3048)
			(end -0.67945 0.3048)
			(stroke
				(width 0.1)
				(type default)
			)
			(layer "F.Fab")
		)
		(fp_line
			(start 0.120396 0.3048)
			(end 0.120396 0.2794)
			(stroke
				(width 0.1)
				(type default)
			)
			(layer "F.Fab")
		)
		(fp_line
			(start 0.67945 0.3048)
			(end 0.120396 0.3048)
			(stroke
				(width 0.1)
				(type default)
			)
			(layer "F.Fab")
		)
		(fp_line
			(start -0.12065 0.2794)
			(end -0.12065 0.3048)
			(stroke
				(width 0.1)
				(type default)
			)
			(layer "F.Fab")
		)
		(fp_line
			(start 0.120396 0.2794)
			(end -0.12065 0.2794)
			(stroke
				(width 0.1)
				(type default)
			)
			(layer "F.Fab")
		)
		(fp_line
			(start -0.12065 -0.2794)
			(end 0.12065 -0.2794)
			(stroke
				(width 0.1)
				(type default)
			)
			(layer "F.Fab")
		)
		(fp_line
			(start 0.12065 -0.2794)
			(end 0.12065 -0.3048)
			(stroke
				(width 0.1)
				(type default)
			)
			(layer "F.Fab")
		)
		(fp_line
			(start 0.12065 -0.3048)
			(end 0.67945 -0.3048)
			(stroke
				(width 0.1)
				(type default)
			)
			(layer "F.Fab")
		)
		(fp_line
			(start 0.67945 -0.3048)
			(end 0.67945 0.3048)
			(stroke
				(width 0.1)
				(type default)
			)
			(layer "F.Fab")
		)
		(fp_line
			(start -0.67945 -0.305054)
			(end -0.12065 -0.305054)
			(stroke
				(width 0.1)
				(type default)
			)
			(layer "F.Fab")
		)
		(fp_line
			(start -0.12065 -0.305054)
			(end -0.12065 -0.2794)
			(stroke
				(width 0.1)
				(type default)
			)
			(layer "F.Fab")
		)
		(pad "1" smd circle
			(at -0.40005 0 270)
			(size 0 0)
			(layers "F.Cu" "F.Mask" "F.Paste")
			(net "P12V_HSC_TEMP_E")
		)
		(pad "2" smd circle
			(at 0.40005 0 270)
			(size 0 0)
			(layers "F.Cu" "F.Mask" "F.Paste")
			(net "P12V_HSC_TEMP_D-")
		)
	)
)
